# S9S_MB_2U (Grand Teton) — schematic netlist excerpt (pin names and nets, part order shuffled) for the footprints in the layout excerpt that follows; sources: Cadence DE-HDL packaged netlist, KiCad conversion of 03242023_DA0F0TMBIJ0_F0T_Motherboard_J_brd_V01_OCP.brd

C2360  Q_CAP  0.1UF 25V 10% X7R  pkg 0402  page 260 : A = P3V3 ; B = GND
R4520  Q_RES  10K 1% CHIP  pkg 0402LF  page 211 : A = P3V3 ; B = CLK_SWB_BUF2_OE_N

(kicad_pcb
	(version 20260206)
	(generator "pcbnew")
	(generator_version "10.0")
	(general
		(thickness 1.6)
		(legacy_teardrops no)
	)
	(paper "A4")
	(title_block
		(title "03242023_DA0F0TMBIJ0_F0T_Motherboard_J_brd_V01_OCP.brd")
		(comment 1 "Grand Teton / footprints 415-416 of 6105")
	)
	(layers
		(0 "F.Cu" signal "TOP")
		(4 "In1.Cu" signal "GND")
		(6 "In2.Cu" signal "IN1")
		(8 "In3.Cu" signal "GND1")
		(10 "In4.Cu" signal "IN2")
		(12 "In5.Cu" signal "GND2")
		(14 "In6.Cu" signal "IN3")
		(16 "In7.Cu" signal "GND3")
		(18 "In8.Cu" signal "VCC")
		(20 "In9.Cu" signal "VCC1")
		(22 "In10.Cu" signal "GND4")
		(24 "In11.Cu" signal "IN4")
		(26 "In12.Cu" signal "GND5")
		(28 "In13.Cu" signal "IN5")
		(30 "In14.Cu" signal "GND6")
		(32 "In15.Cu" signal "IN6")
		(34 "In16.Cu" signal "GND7")
		(2 "B.Cu" signal "BOTTOM")
		(9 "F.Adhes" user "F.Adhesive")
		(11 "B.Adhes" user "B.Adhesive")
		(13 "F.Paste" user "Package Geometry/Pastemask Top")
		(15 "B.Paste" user "Package Geometry/Pastemask Bottom")
		(5 "F.SilkS" user "Ref Des/Silkscreen Top")
		(7 "B.SilkS" user "Ref Des/Silkscreen Bottom")
		(1 "F.Mask" user "Board Geometry/Soldermask Top")
		(3 "B.Mask" user "Board Geometry/Soldermask Bottom")
		(17 "Dwgs.User" user "User.Drawings")
		(19 "Cmts.User" user "User.Comments")
		(21 "Eco1.User" user "User.Eco1")
		(23 "Eco2.User" user "User.Eco2")
		(25 "Edge.Cuts" user "Board Geometry/Outline")
		(27 "Margin" user)
		(31 "F.CrtYd" user "Package Geometry/Place Bound Top")
		(29 "B.CrtYd" user "Package Geometry/Place Bound Bottom")
		(35 "F.Fab" user "Ref Des/Assembly Top")
		(33 "B.Fab" user "Ref Des/Assembly Bottom")
	)
	(footprint ""
		(layer "F.Cu")
		(at 193.3829 -126.405386)
		(property "Reference" "R4520"
			(at 0 0 0)
			(layer "F.SilkS")
			(hide yes)
			(effects
				(font
					(size 1.27 1.27)
				)
			)
		)
		(property "Value" ""
			(at 0 0 0)
			(layer "F.Fab")
			(effects
				(font
					(size 1.27 1.27)
				)
			)
		)
		(duplicate_pad_numbers_are_jumpers no)
		(fp_line
			(start -0.7874 -0.4064)
			(end 0.7874 -0.4064)
			(stroke
				(width 0.1524)
				(type default)
			)
			(layer "F.SilkS")
		)
		(fp_line
			(start -0.7874 0.4064)
			(end -0.7874 -0.4064)
			(stroke
				(width 0.1524)
				(type default)
			)
			(layer "F.SilkS")
		)
		(fp_line
			(start 0.7874 -0.4064)
			(end 0.7874 0.4064)
			(stroke
				(width 0.1524)
				(type default)
			)
			(layer "F.SilkS")
		)
		(fp_line
			(start 0.7874 0.4064)
			(end -0.7874 0.4064)
			(stroke
				(width 0.1524)
				(type default)
			)
			(layer "F.SilkS")
		)
		(fp_line
			(start -0.67945 -0.305054)
			(end -0.12065 -0.305054)
			(stroke
				(width 0.1)
				(type default)
			)
			(layer "F.Fab")
		)
		(fp_line
			(start -0.67945 0.3048)
			(end -0.67945 -0.305054)
			(stroke
				(width 0.1)
				(type default)
			)
			(layer "F.Fab")
		)
		(fp_line
			(start -0.12065 -0.305054)
			(end -0.12065 -0.2794)
			(stroke
				(width 0.1)
				(type default)
			)
			(layer "F.Fab")
		)
		(fp_line
			(start -0.12065 -0.2794)
			(end 0.12065 -0.2794)
			(stroke
				(width 0.1)
				(type default)
			)
			(layer "F.Fab")
		)
		(fp_line
			(start -0.12065 0.2794)
			(end -0.12065 0.3048)
			(stroke
				(width 0.1)
				(type default)
			)
			(layer "F.Fab")
		)
		(fp_line
			(start -0.12065 0.3048)
			(end -0.67945 0.3048)
			(stroke
				(width 0.1)
				(type default)
			)
			(layer "F.Fab")
		)
		(fp_line
			(start 0.120396 0.2794)
			(end -0.12065 0.2794)
			(stroke
				(width 0.1)
				(type default)
			)
			(layer "F.Fab")
		)
		(fp_line
			(start 0.120396 0.3048)
			(end 0.120396 0.2794)
			(stroke
				(width 0.1)
				(type default)
			)
			(layer "F.Fab")
		)
		(fp_line
			(start 0.12065 -0.3048)
			(end 0.67945 -0.3048)
			(stroke
				(width 0.1)
				(type default)
			)
			(layer "F.Fab")
		)
		(fp_line
			(start 0.12065 -0.2794)
			(end 0.12065 -0.3048)
			(stroke
				(width 0.1)
				(type default)
			)
			(layer "F.Fab")
		)
		(fp_line
			(start 0.67945 -0.3048)
			(end 0.67945 0.3048)
			(stroke
				(width 0.1)
				(type default)
			)
			(layer "F.Fab")
		)
		(fp_line
			(start 0.67945 0.3048)
			(end 0.120396 0.3048)
			(stroke
				(width 0.1)
				(type default)
			)
			(layer "F.Fab")
		)
		(pad "1" smd circle
			(at -0.40005 0)
			(size 0 0)
			(layers "F.Cu" "F.Mask" "F.Paste")
			(net "P3V3")
		)
		(pad "2" smd circle
			(at 0.40005 0)
			(size 0 0)
			(layers "F.Cu" "F.Mask" "F.Paste")
			(net "CLK_SWB_BUF2_OE_N")
		)
	)
	(footprint ""
		(layer "F.Cu")
		(at 424.98772 -51.22418 180)
		(property "Reference" "C2360"
			(at 0 0 180)
			(layer "F.SilkS")
			(hide yes)
			(effects
				(font
					(size 1.27 1.27)
				)
			)
		)
		(property "Value" ""
			(at 0 0 180)
			(layer "F.Fab")
			(effects
				(font
					(size 1.27 1.27)
				)
			)
		)
		(duplicate_pad_numbers_are_jumpers no)
		(fp_line
			(start 0.7874 0.4064)
			(end -0.7874 0.4064)
			(stroke
				(width 0.1524)
				(type default)
			)
			(layer "F.SilkS")
		)
		(fp_line
			(start 0.7874 -0.4064)
			(end 0.7874 0.4064)
			(stroke
				(width 0.1524)
				(type default)
			)
			(layer "F.SilkS")
		)
		(fp_line
			(start -0.7874 0.4064)
			(end -0.7874 -0.4064)
			(stroke
				(width 0.1524)
				(type default)
			)
			(layer "F.SilkS")
		)
		(fp_line
			(start -0.7874 -0.4064)
			(end 0.7874 -0.4064)
			(stroke
				(width 0.1524)
				(type default)
			)
			(layer "F.SilkS")
		)
		(fp_line
			(start 0.6858 0.3048)
			(end 0.1016 0.3048)
			(stroke
				(width 0.1)
				(type default)
			)
			(layer "F.Fab")
		)
		(fp_line
			(start 0.6858 -0.3048)
			(end 0.6858 0.3048)
			(stroke
				(width 0.1)
				(type default)
			)
			(layer "F.Fab")
		)
		(fp_line
			(start 0.1016 0.3048)
			(end 0.1016 0.2794)
			(stroke
				(width 0.1)
				(type default)
			)
			(layer "F.Fab")
		)
		(fp_line
			(start 0.1016 0.2794)
			(end -0.1016 0.2794)
			(stroke
				(width 0.1)
				(type default)
			)
			(layer "F.Fab")
		)
		(fp_line
			(start 0.1016 -0.2794)
			(end 0.1016 -0.3048)
			(stroke
				(width 0.1)
				(type default)
			)
			(layer "F.Fab")
		)
		(fp_line
			(start 0.1016 -0.3048)
			(end 0.6858 -0.3048)
			(stroke
				(width 0.1)
				(type default)
			)
			(layer "F.Fab")
		)
		(fp_line
			(start -0.1016 0.3048)
			(end -0.6858 0.3048)
			(stroke
				(width 0.1)
				(type default)
			)
			(layer "F.Fab")
		)
		(fp_line
			(start -0.1016 0.2794)
			(end -0.1016 0.3048)
			(stroke
				(width 0.1)
				(type default)
			)
			(layer "F.Fab")
		)
		(fp_line
			(start -0.1016 -0.2794)
			(end 0.1016 -0.2794)
			(stroke
				(width 0.1)
				(type default)
			)
			(layer "F.Fab")
		)
		(fp_line
			(start -0.1016 -0.3048)
			(end -0.1016 -0.2794)
			(stroke
				(width 0.1)
				(type default)
			)
			(layer "F.Fab")
		)
		(fp_line
			(start -0.6858 0.3048)
			(end -0.6858 -0.3048)
			(stroke
				(width 0.1)
				(type default)
			)
			(layer "F.Fab")
		)
		(fp_line
			(start -0.6858 -0.3048)
			(end -0.1016 -0.3048)
			(stroke
				(width 0.1)
				(type default)
			)
			(layer "F.Fab")
		)
		(pad "1" smd rect
			(at -0.40005 0)
			(size 0.4572 0.508)
			(layers "F.Cu" "F.Mask" "F.Paste")
			(net "P3V3")
		)
		(pad "2" smd rect
			(at 0.40005 0)
			(size 0.4572 0.508)
			(layers "F.Cu" "F.Mask" "F.Paste")
			(net "GND")
		)
	)
)
